# T6G (Grand Teton) — schematic netlist excerpt (pin names and nets, part order shuffled) for the footprints in the layout excerpt that follows; sources: Cadence DE-HDL packaged netlist, KiCad conversion of 04192023_DAF0TMB3IC0_F0TG_MB_C_brd_V02_OCP.brd

R405  Q_RES  0 5% CHIP  pkg 0402LF  page 27 : A = UART_CPU0_UART0_TX ; B = UART_CPU0_UART0_R_TX

(kicad_pcb
	(version 20260206)
	(generator "pcbnew")
	(generator_version "10.0")
	(general
		(thickness 1.6)
		(legacy_teardrops no)
	)
	(paper "A4")
	(title_block
		(title "04192023_DAF0TMB3IC0_F0TG_MB_C_brd_V02_OCP.brd")
		(comment 1 "Grand Teton / footprints 5337-5337 of 8354")
	)
	(layers
		(0 "F.Cu" signal "TOP")
		(4 "In1.Cu" signal "GND")
		(6 "In2.Cu" signal "IN1")
		(8 "In3.Cu" signal "GND1")
		(10 "In4.Cu" signal "IN2")
		(12 "In5.Cu" signal "GND2")
		(14 "In6.Cu" signal "IN3")
		(16 "In7.Cu" signal "GND3")
		(18 "In8.Cu" signal "VCC")
		(20 "In9.Cu" signal "VCC1")
		(22 "In10.Cu" signal "GND4")
		(24 "In11.Cu" signal "IN4")
		(26 "In12.Cu" signal "GND5")
		(28 "In13.Cu" signal "IN5")
		(30 "In14.Cu" signal "GND6")
		(32 "In15.Cu" signal "IN6")
		(34 "In16.Cu" signal "GND7")
		(2 "B.Cu" signal "BOTTOM")
		(9 "F.Adhes" user "F.Adhesive")
		(11 "B.Adhes" user "B.Adhesive")
		(13 "F.Paste" user "Package Geometry/Pastemask Top")
		(15 "B.Paste" user "Package Geometry/Pastemask Bottom")
		(5 "F.SilkS" user "Ref Des/Silkscreen Top")
		(7 "B.SilkS" user "Ref Des/Silkscreen Bottom")
		(1 "F.Mask" user "Board Geometry/Soldermask Top")
		(3 "B.Mask" user "Board Geometry/Soldermask Bottom")
		(17 "Dwgs.User" user "User.Drawings")
		(19 "Cmts.User" user "User.Comments")
		(21 "Eco1.User" user "User.Eco1")
		(23 "Eco2.User" user "User.Eco2")
		(25 "Edge.Cuts" user "Board Geometry/Outline")
		(27 "Margin" user)
		(31 "F.CrtYd" user "Package Geometry/Place Bound Top")
		(29 "B.CrtYd" user "Package Geometry/Place Bound Bottom")
		(35 "F.Fab" user "Ref Des/Assembly Top")
		(33 "B.Fab" user "Ref Des/Assembly Bottom")
	)
	(footprint ""
		(layer "B.Cu")
		(at 346.026994 -308.517798)
		(property "Reference" "R405"
			(at 0 0 0)
			(layer "B.SilkS")
			(hide yes)
			(effects
				(font
					(size 1.27 1.27)
				)
				(justify mirror)
			)
		)
		(property "Value" ""
			(at 0 0 0)
			(layer "B.Fab")
			(effects
				(font
					(size 1.27 1.27)
				)
				(justify mirror)
			)
		)
		(duplicate_pad_numbers_are_jumpers no)
		(fp_line
			(start -0.7874 -0.4064)
			(end -0.7874 0.4064)
			(stroke
				(width 0.1524)
				(type default)
			)
			(layer "B.SilkS")
		)
		(fp_line
			(start -0.7874 0.4064)
			(end 0.7874 0.4064)
			(stroke
				(width 0.1524)
				(type default)
			)
			(layer "B.SilkS")
		)
		(fp_line
			(start 0.7874 -0.4064)
			(end -0.7874 -0.4064)
			(stroke
				(width 0.1524)
				(type default)
			)
			(layer "B.SilkS")
		)
		(fp_line
			(start 0.7874 0.4064)
			(end 0.7874 -0.4064)
			(stroke
				(width 0.1524)
				(type default)
			)
			(layer "B.SilkS")
		)
		(fp_line
			(start -0.67945 -0.3048)
			(end -0.67945 0.3048)
			(stroke
				(width 0.1)
				(type default)
			)
			(layer "B.Fab")
		)
		(fp_line
			(start -0.67945 0.3048)
			(end -0.120396 0.3048)
			(stroke
				(width 0.1)
				(type default)
			)
			(layer "B.Fab")
		)
		(fp_line
			(start -0.12065 -0.3048)
			(end -0.67945 -0.3048)
			(stroke
				(width 0.1)
				(type default)
			)
			(layer "B.Fab")
		)
		(fp_line
			(start -0.12065 -0.2794)
			(end -0.12065 -0.3048)
			(stroke
				(width 0.1)
				(type default)
			)
			(layer "B.Fab")
		)
		(fp_line
			(start -0.120396 0.2794)
			(end 0.12065 0.2794)
			(stroke
				(width 0.1)
				(type default)
			)
			(layer "B.Fab")
		)
		(fp_line
			(start -0.120396 0.3048)
			(end -0.120396 0.2794)
			(stroke
				(width 0.1)
				(type default)
			)
			(layer "B.Fab")
		)
		(fp_line
			(start 0.12065 -0.305054)
			(end 0.12065 -0.2794)
			(stroke
				(width 0.1)
				(type default)
			)
			(layer "B.Fab")
		)
		(fp_line
			(start 0.12065 -0.2794)
			(end -0.12065 -0.2794)
			(stroke
				(width 0.1)
				(type default)
			)
			(layer "B.Fab")
		)
		(fp_line
			(start 0.12065 0.2794)
			(end 0.12065 0.3048)
			(stroke
				(width 0.1)
				(type default)
			)
			(layer "B.Fab")
		)
		(fp_line
			(start 0.12065 0.3048)
			(end 0.67945 0.3048)
			(stroke
				(width 0.1)
				(type default)
			)
			(layer "B.Fab")
		)
		(fp_line
			(start 0.67945 -0.305054)
			(end 0.12065 -0.305054)
			(stroke
				(width 0.1)
				(type default)
			)
			(layer "B.Fab")
		)
		(fp_line
			(start 0.67945 0.3048)
			(end 0.67945 -0.305054)
			(stroke
				(width 0.1)
				(type default)
			)
			(layer "B.Fab")
		)
		(pad "1" smd circle
			(at 0.40005 0 180)
			(size 0 0)
			(layers "B.Cu" "B.Mask" "B.Paste")
			(net "UART_CPU0_UART0_TX")
		)
		(pad "2" smd circle
			(at -0.40005 0 180)
			(size 0 0)
			(layers "B.Cu" "B.Mask" "B.Paste")
			(net "UART_CPU0_UART0_R_TX")
		)
	)
)
